(kicad_pcb
	(version 20241229)
	(generator "pcbnew")
	(generator_version "9.0")
	(general
		(thickness 1.552)
		(legacy_teardrops no)
	)
	(paper "A4")
	(title_block
		(date "2023-07-25")
		(rev "1.1.4")
		(comment 9 "footprints 7-11 of 379")
	)
	(layers
		(0 "F.Cu" signal)
		(4 "In1.Cu" signal)
		(6 "In2.Cu" signal)
		(8 "In3.Cu" signal)
		(10 "In4.Cu" signal)
		(12 "In5.Cu" signal)
		(14 "In6.Cu" signal)
		(2 "B.Cu" signal)
		(9 "F.Adhes" user "F.Adhesive")
		(11 "B.Adhes" user "B.Adhesive")
		(13 "F.Paste" user)
		(15 "B.Paste" user)
		(5 "F.SilkS" user "F.Silkscreen")
		(7 "B.SilkS" user "B.Silkscreen")
		(1 "F.Mask" user)
		(3 "B.Mask" user)
		(17 "Dwgs.User" user "User.Drawings")
		(19 "Cmts.User" user "User.Comments")
		(21 "Eco1.User" user "User.Eco1")
		(23 "Eco2.User" user "User.Eco2")
		(25 "Edge.Cuts" user)
		(27 "Margin" user)
		(31 "F.CrtYd" user "F.Courtyard")
		(29 "B.CrtYd" user "B.Courtyard")
		(35 "F.Fab" user)
		(33 "B.Fab" user)
	)
	(footprint "antmicro-footprints:R_0603_1608Metric"
		(layer "F.Cu")
		(at 158.29 82.7 180)
		(descr "Resistor SMD 0603")
		(tags "resistor SMD 0603")
		(property "Reference" "R115"
			(at 4.06 -0.44 180)
			(layer "F.SilkS")
			(effects
				(font
					(size 0.65 0.65)
					(thickness 0.15)
				)
				(justify left bottom)
			)
		)
		(property "Value" "R_10k_0603"
			(at 0 1.6 180)
			(layer "F.Fab")
			(hide yes)
			(effects
				(font
					(size 0.7 0.7)
					(thickness 0.15)
				)
				(justify left bottom)
			)
		)
		(property "Datasheet" "https://www.bourns.com/docs/product-datasheets/cr.pdf"
			(at 0 0 180)
			(layer "F.Fab")
			(hide yes)
			(effects
				(font
					(size 1.27 1.27)
					(thickness 0.15)
				)
			)
		)
		(property "Description" "SMD Chip Resistor, 10 kohm, ± 1%, 100 mW, 0603 [1608 Metric], Thick Film, General Purpose"
			(at 0 0 180)
			(layer "F.Fab")
			(hide yes)
			(effects
				(font
					(size 1.27 1.27)
					(thickness 0.15)
				)
			)
		)
		(property "Author" "Antmicro"
			(at 316.58 165.4 0)
			(layer "F.Fab")
			(hide yes)
			(effects
				(font
					(size 1 1)
					(thickness 0.15)
				)
			)
		)
		(property "License" "Apache-2.0"
			(at 316.58 165.4 0)
			(layer "F.Fab")
			(hide yes)
			(effects
				(font
					(size 1 1)
					(thickness 0.15)
				)
			)
		)
		(property "MPN" "CR0603-FX-1002ELF"
			(at 316.58 165.4 0)
			(layer "F.Fab")
			(hide yes)
			(effects
				(font
					(size 1 1)
					(thickness 0.15)
				)
			)
		)
		(property "Manufacturer" "Bourns"
			(at 316.58 165.4 0)
			(layer "F.Fab")
			(hide yes)
			(effects
				(font
					(size 1 1)
					(thickness 0.15)
				)
			)
		)
		(property "Tolerance" "1%"
			(at 316.58 165.4 0)
			(layer "F.Fab")
			(hide yes)
			(effects
				(font
					(size 1 1)
					(thickness 0.15)
				)
			)
		)
		(property "Val" "10k"
			(at 316.58 165.4 0)
			(layer "F.Fab")
			(hide yes)
			(effects
				(font
					(size 1 1)
					(thickness 0.15)
				)
			)
		)
		(sheetname "/Peripherals/")
		(sheetfile "peripherals.kicad_sch")
		(attr smd exclude_from_pos_files exclude_from_bom dnp)
		(fp_line
			(start -0.15 0.4)
			(end 0.15 0.4)
			(stroke
				(width 0.15)
				(type solid)
			)
			(layer "F.SilkS")
		)
		(fp_line
			(start -0.15 -0.4)
			(end 0.15 -0.4)
			(stroke
				(width 0.15)
				(type solid)
			)
			(layer "F.SilkS")
		)
		(fp_rect
			(start -1.25 -0.65)
			(end 1.25 0.65)
			(stroke
				(width 0.05)
				(type solid)
			)
			(fill no)
			(layer "F.CrtYd")
		)
		(fp_rect
			(start -0.8 -0.4)
			(end 0.8 0.4)
			(stroke
				(width 0.15)
				(type solid)
			)
			(fill no)
			(layer "F.Fab")
		)
		(fp_text user "Author: Antmicro"
			(at -1.25 4.9 180)
			(layer "F.Fab")
			(effects
				(font
					(size 0.7 0.7)
					(thickness 0.15)
				)
				(justify left bottom)
			)
		)
		(fp_text user "License: Apache-2.0"
			(at -1.25 5.9 180)
			(layer "F.Fab")
			(effects
				(font
					(size 0.7 0.7)
					(thickness 0.15)
				)
				(justify left bottom)
			)
		)
		(fp_text user "${REFERENCE}"
			(at -1.25 3.898 180)
			(layer "F.Fab")
			(effects
				(font
					(size 0.7 0.7)
					(thickness 0.15)
				)
				(justify left bottom)
			)
		)
		(pad "1" smd roundrect
			(at -0.7 0 180)
			(size 0.8 1)
			(layers "F.Cu" "F.Mask" "F.Paste")
			(roundrect_rratio 0.2)
			(net 315 "/Peripherals/QWIIC_PEN")
			(pintype "passive")
		)
		(pad "2" smd roundrect
			(at 0.7 0 180)
			(size 0.8 1)
			(layers "F.Cu" "F.Mask" "F.Paste")
			(roundrect_rratio 0.2)
			(net 1 "GND")
			(pintype "passive")
		)
	)
	(footprint "antmicro-footprints:TP_SMD_0.75mm"
		(layer "F.Cu")
		(at 140.33 69.25 90)
		(property "Reference" "TP10"
			(at 0 -0.6 90)
			(layer "F.SilkS")
			(effects
				(font
					(size 0.65 0.65)
					(thickness 0.15)
				)
				(justify left bottom)
			)
		)
		(property "Value" "TP_0.75mm_SMD"
			(at 0 1.2 90)
			(layer "F.Fab")
			(hide yes)
			(effects
				(font
					(size 0.7 0.7)
					(thickness 0.15)
				)
				(justify left bottom)
			)
		)
		(property "Description" "SMT test point"
			(at 0 0 90)
			(layer "F.Fab")
			(hide yes)
			(effects
				(font
					(size 1.27 1.27)
					(thickness 0.15)
				)
			)
		)
		(property "Author" "Antmicro"
			(at 209.58 -71.08 0)
			(layer "F.Fab")
			(hide yes)
			(effects
				(font
					(size 1 1)
					(thickness 0.15)
				)
			)
		)
		(property "License" "Apache-2.0"
			(at 209.58 -71.08 0)
			(layer "F.Fab")
			(hide yes)
			(effects
				(font
					(size 1 1)
					(thickness 0.15)
				)
			)
		)
		(property "MPN" ""
			(at 209.58 -71.08 0)
			(layer "F.Fab")
			(hide yes)
			(effects
				(font
					(size 1 1)
					(thickness 0.15)
				)
			)
		)
		(property "Manufacturer" ""
			(at 209.58 -71.08 0)
			(layer "F.Fab")
			(hide yes)
			(effects
				(font
					(size 1 1)
					(thickness 0.15)
				)
			)
		)
		(sheetname "/Power Supply/")
		(sheetfile "supply.kicad_sch")
		(attr exclude_from_pos_files)
		(fp_circle
			(center 0 0)
			(end 0.475 0)
			(stroke
				(width 0.05)
				(type default)
			)
			(fill no)
			(layer "F.CrtYd")
		)
		(fp_text user "Author: Antmicro"
			(at -0.4 3.901 90)
			(layer "F.Fab")
			(effects
				(font
					(size 0.7 0.7)
					(thickness 0.15)
				)
				(justify left bottom)
			)
		)
		(fp_text user "License: Apache-2.0"
			(at -0.4 5.101 90)
			(layer "F.Fab")
			(effects
				(font
					(size 0.7 0.7)
					(thickness 0.15)
				)
				(justify left bottom)
			)
		)
		(fp_text user "${REFERENCE}"
			(at -0.4 2.7 90)
			(layer "F.Fab")
			(effects
				(font
					(size 0.7 0.7)
					(thickness 0.15)
				)
				(justify left bottom)
			)
		)
		(pad "1" smd circle
			(at 0 0 90)
			(size 0.75 0.75)
			(layers "F.Cu" "F.Mask")
			(net 373 "Net-(U5-EN)")
			(pinfunction "1")
			(pintype "passive")
		)
	)
	(footprint "antmicro-footprints:R_0603_1608Metric"
		(layer "F.Cu")
		(at 169.83 80.968952 180)
		(descr "Resistor SMD 0603")
		(tags "resistor SMD 0603")
		(property "Reference" "R102"
			(at 4.1 -0.29 180)
			(layer "F.SilkS")
			(effects
				(font
					(size 0.65 0.65)
					(thickness 0.15)
				)
				(justify left bottom)
			)
		)
		(property "Value" "R_200R_0603"
			(at 0 1.6 180)
			(layer "F.Fab")
			(hide yes)
			(effects
				(font
					(size 0.7 0.7)
					(thickness 0.15)
				)
				(justify left bottom)
			)
		)
		(property "Datasheet" "https://www.bourns.com/docs/product-datasheets/cr.pdf"
			(at 0 0 180)
			(layer "F.Fab")
			(hide yes)
			(effects
				(font
					(size 1.27 1.27)
					(thickness 0.15)
				)
			)
		)
		(property "Description" "SMD Chip Resistor, 200 ohm, ± 1%, 100 mW, 0603 [1608 Metric], Thick Film, General Purpose"
			(at 0 0 180)
			(layer "F.Fab")
			(hide yes)
			(effects
				(font
					(size 1.27 1.27)
					(thickness 0.15)
				)
			)
		)
		(property "Author" "Antmicro"
			(at 339.66 161.9 0)
			(layer "F.Fab")
			(hide yes)
			(effects
				(font
					(size 1 1)
					(thickness 0.15)
				)
			)
		)
		(property "License" "Apache-2.0"
			(at 339.66 161.9 0)
			(layer "F.Fab")
			(hide yes)
			(effects
				(font
					(size 1 1)
					(thickness 0.15)
				)
			)
		)
		(property "MPN" "CR0603-FX-2000ELF"
			(at 339.66 161.9 0)
			(layer "F.Fab")
			(hide yes)
			(effects
				(font
					(size 1 1)
					(thickness 0.15)
				)
			)
		)
		(property "Manufacturer" "Bourns"
			(at 339.66 161.9 0)
			(layer "F.Fab")
			(hide yes)
			(effects
				(font
					(size 1 1)
					(thickness 0.15)
				)
			)
		)
		(property "Tolerance" "1%"
			(at 339.66 161.9 0)
			(layer "F.Fab")
			(hide yes)
			(effects
				(font
					(size 1 1)
					(thickness 0.15)
				)
			)
		)
		(property "Val" "200R"
			(at 339.66 161.9 0)
			(layer "F.Fab")
			(hide yes)
			(effects
				(font
					(size 1 1)
					(thickness 0.15)
				)
			)
		)
		(sheetname "/Peripherals/")
		(sheetfile "peripherals.kicad_sch")
		(attr smd)
		(fp_line
			(start -0.15 0.4)
			(end 0.15 0.4)
			(stroke
				(width 0.15)
				(type solid)
			)
			(layer "F.SilkS")
		)
		(fp_line
			(start -0.15 -0.4)
			(end 0.15 -0.4)
			(stroke
				(width 0.15)
				(type solid)
			)
			(layer "F.SilkS")
		)
		(fp_rect
			(start -1.25 -0.65)
			(end 1.25 0.65)
			(stroke
				(width 0.05)
				(type solid)
			)
			(fill no)
			(layer "F.CrtYd")
		)
		(fp_rect
			(start -0.8 -0.4)
			(end 0.8 0.4)
			(stroke
				(width 0.15)
				(type solid)
			)
			(fill no)
			(layer "F.Fab")
		)
		(fp_text user "License: Apache-2.0"
			(at -1.25 5.9 180)
			(layer "F.Fab")
			(effects
				(font
					(size 0.7 0.7)
					(thickness 0.15)
				)
				(justify left bottom)
			)
		)
		(fp_text user "${REFERENCE}"
			(at -1.25 3.898 180)
			(layer "F.Fab")
			(effects
				(font
					(size 0.7 0.7)
					(thickness 0.15)
				)
				(justify left bottom)
			)
		)
		(fp_text user "Author: Antmicro"
			(at -1.25 4.9 180)
			(layer "F.Fab")
			(effects
				(font
					(size 0.7 0.7)
					(thickness 0.15)
				)
				(justify left bottom)
			)
		)
		(pad "1" smd roundrect
			(at -0.7 0 180)
			(size 0.8 1)
			(layers "F.Cu" "F.Mask" "F.Paste")
			(roundrect_rratio 0.2)
			(net 255 "Net-(D9-A)")
			(pintype "passive")
		)
		(pad "2" smd roundrect
			(at 0.7 0 180)
			(size 0.8 1)
			(layers "F.Cu" "F.Mask" "F.Paste")
			(roundrect_rratio 0.2)
			(net 17 "/Peripherals/FFC1_3V3")
			(pintype "passive")
		)
	)
	(footprint "antmicro-footprints:R_0603_1608Metric"
		(layer "F.Cu")
		(at 163.63 123.75 180)
		(descr "Resistor SMD 0603")
		(tags "resistor SMD 0603")
		(property "Reference" "R119"
			(at -4.2 -0.39 0)
			(layer "F.SilkS")
			(effects
				(font
					(size 0.65 0.65)
					(thickness 0.15)
				)
				(justify right bottom)
			)
		)
		(property "Value" "R_0R_0603"
			(at 0 1.6 0)
			(layer "F.Fab")
			(hide yes)
			(effects
				(font
					(size 0.7 0.7)
					(thickness 0.15)
				)
				(justify right bottom)
			)
		)
		(property "Datasheet" "https://www.bourns.com/docs/product-datasheets/cr.pdf?sfvrsn=574d41f6_14"
			(at 0 0 180)
			(layer "F.Fab")
			(hide yes)
			(effects
				(font
					(size 1.27 1.27)
					(thickness 0.15)
				)
			)
		)
		(property "Description" "Zero Ohm Resistor, Jumper, 0603 [1608 Metric], Thick Film, 100 mW, 1 A, Surface Mount Device, CR"
			(at 0 0 180)
			(layer "F.Fab")
			(hide yes)
			(effects
				(font
					(size 1.27 1.27)
					(thickness 0.15)
				)
			)
		)
		(property "Author" "Antmicro"
			(at 327.26 247.5 0)
			(layer "F.Fab")
			(hide yes)
			(effects
				(font
					(size 1 1)
					(thickness 0.15)
				)
			)
		)
		(property "Current" "1A"
			(at 327.26 247.5 0)
			(layer "F.Fab")
			(hide yes)
			(effects
				(font
					(size 1 1)
					(thickness 0.15)
				)
			)
		)
		(property "License" "Apache-2.0"
			(at 327.26 247.5 0)
			(layer "F.Fab")
			(hide yes)
			(effects
				(font
					(size 1 1)
					(thickness 0.15)
				)
			)
		)
		(property "MPN" "CR0603-J/-000ELF"
			(at 327.26 247.5 0)
			(layer "F.Fab")
			(hide yes)
			(effects
				(font
					(size 1 1)
					(thickness 0.15)
				)
			)
		)
		(property "Manufacturer" "Bourns"
			(at 327.26 247.5 0)
			(layer "F.Fab")
			(hide yes)
			(effects
				(font
					(size 1 1)
					(thickness 0.15)
				)
			)
		)
		(property "Tolerance" "~"
			(at 327.26 247.5 0)
			(layer "F.Fab")
			(hide yes)
			(effects
				(font
					(size 1 1)
					(thickness 0.15)
				)
			)
		)
		(property "Val" "0R"
			(at 327.26 247.5 0)
			(layer "F.Fab")
			(hide yes)
			(effects
				(font
					(size 1 1)
					(thickness 0.15)
				)
			)
		)
		(sheetname "/Peripherals/")
		(sheetfile "peripherals.kicad_sch")
		(attr smd)
		(fp_line
			(start -0.15 0.4)
			(end 0.15 0.4)
			(stroke
				(width 0.15)
				(type solid)
			)
			(layer "F.SilkS")
		)
		(fp_line
			(start -0.15 -0.4)
			(end 0.15 -0.4)
			(stroke
				(width 0.15)
				(type solid)
			)
			(layer "F.SilkS")
		)
		(fp_rect
			(start -1.25 -0.65)
			(end 1.25 0.65)
			(stroke
				(width 0.05)
				(type solid)
			)
			(fill no)
			(layer "F.CrtYd")
		)
		(fp_rect
			(start -0.8 -0.4)
			(end 0.8 0.4)
			(stroke
				(width 0.15)
				(type solid)
			)
			(fill no)
			(layer "F.Fab")
		)
		(fp_text user "${REFERENCE}"
			(at -1.25 3.898 180)
			(layer "F.Fab")
			(effects
				(font
					(size 0.7 0.7)
					(thickness 0.15)
				)
				(justify left bottom)
			)
		)
		(fp_text user "License: Apache-2.0"
			(at -1.25 5.9 180)
			(layer "F.Fab")
			(effects
				(font
					(size 0.7 0.7)
					(thickness 0.15)
				)
				(justify left bottom)
			)
		)
		(fp_text user "Author: Antmicro"
			(at -1.25 4.9 180)
			(layer "F.Fab")
			(effects
				(font
					(size 0.7 0.7)
					(thickness 0.15)
				)
				(justify left bottom)
			)
		)
		(pad "1" smd roundrect
			(at -0.7 0 180)
			(size 0.8 1)
			(layers "F.Cu" "F.Mask" "F.Paste")
			(roundrect_rratio 0.2)
			(net 315 "/Peripherals/QWIIC_PEN")
			(pintype "passive")
		)
		(pad "2" smd roundrect
			(at 0.7 0 180)
			(size 0.8 1)
			(layers "F.Cu" "F.Mask" "F.Paste")
			(roundrect_rratio 0.2)
			(net 335 "GPIO3")
			(pintype "passive")
		)
	)
	(footprint "antmicro-footprints:R_0603_1608Metric"
		(layer "F.Cu")
		(at 158.53 91.65 -90)
		(descr "Resistor SMD 0603")
		(tags "resistor SMD 0603")
		(property "Reference" "R104"
			(at -1.31 1.52 90)
			(layer "F.SilkS")
			(effects
				(font
					(size 0.65 0.65)
					(thickness 0.15)
				)
				(justify right top)
			)
		)
		(property "Value" "R_10k_0603"
			(at 0 1.6 90)
			(layer "F.Fab")
			(hide yes)
			(effects
				(font
					(size 0.7 0.7)
					(thickness 0.15)
				)
				(justify right top)
			)
		)
		(property "Datasheet" "https://www.bourns.com/docs/product-datasheets/cr.pdf"
			(at 0 0 90)
			(layer "F.Fab")
			(hide yes)
			(effects
				(font
					(size 1.27 1.27)
					(thickness 0.15)
				)
			)
		)
		(property "Description" "SMD Chip Resistor, 10 kohm, ± 1%, 100 mW, 0603 [1608 Metric], Thick Film, General Purpose"
			(at 0 0 90)
			(layer "F.Fab")
			(hide yes)
			(effects
				(font
					(size 1.27 1.27)
					(thickness 0.15)
				)
			)
		)
		(property "Author" "Antmicro"
			(at 66.88 250.18 0)
			(layer "F.Fab")
			(hide yes)
			(effects
				(font
					(size 1 1)
					(thickness 0.15)
				)
			)
		)
		(property "License" "Apache-2.0"
			(at 66.88 250.18 0)
			(layer "F.Fab")
			(hide yes)
			(effects
				(font
					(size 1 1)
					(thickness 0.15)
				)
			)
		)
		(property "MPN" "CR0603-FX-1002ELF"
			(at 66.88 250.18 0)
			(layer "F.Fab")
			(hide yes)
			(effects
				(font
					(size 1 1)
					(thickness 0.15)
				)
			)
		)
		(property "Manufacturer" "Bourns"
			(at 66.88 250.18 0)
			(layer "F.Fab")
			(hide yes)
			(effects
				(font
					(size 1 1)
					(thickness 0.15)
				)
			)
		)
		(property "Tolerance" "1%"
			(at 66.88 250.18 0)
			(layer "F.Fab")
			(hide yes)
			(effects
				(font
					(size 1 1)
					(thickness 0.15)
				)
			)
		)
		(property "Val" "10k"
			(at 66.88 250.18 0)
			(layer "F.Fab")
			(hide yes)
			(effects
				(font
					(size 1 1)
					(thickness 0.15)
				)
			)
		)
		(sheetname "/Peripherals/")
		(sheetfile "peripherals.kicad_sch")
		(attr smd)
		(fp_line
			(start -0.15 0.4)
			(end 0.15 0.4)
			(stroke
				(width 0.15)
				(type solid)
			)
			(layer "F.SilkS")
		)
		(fp_line
			(start -0.15 -0.4)
			(end 0.15 -0.4)
			(stroke
				(width 0.15)
				(type solid)
			)
			(layer "F.SilkS")
		)
		(fp_rect
			(start -1.25 -0.65)
			(end 1.25 0.65)
			(stroke
				(width 0.05)
				(type solid)
			)
			(fill no)
			(layer "F.CrtYd")
		)
		(fp_rect
			(start -0.8 -0.4)
			(end 0.8 0.4)
			(stroke
				(width 0.15)
				(type solid)
			)
			(fill no)
			(layer "F.Fab")
		)
		(fp_text user "Author: Antmicro"
			(at -1.25 4.9 270)
			(layer "F.Fab")
			(effects
				(font
					(size 0.7 0.7)
					(thickness 0.15)
				)
				(justify left bottom)
			)
		)
		(fp_text user "License: Apache-2.0"
			(at -1.25 5.9 270)
			(layer "F.Fab")
			(effects
				(font
					(size 0.7 0.7)
					(thickness 0.15)
				)
				(justify left bottom)
			)
		)
		(fp_text user "${REFERENCE}"
			(at -1.25 3.898 270)
			(layer "F.Fab")
			(effects
				(font
					(size 0.7 0.7)
					(thickness 0.15)
				)
				(justify left bottom)
			)
		)
		(pad "1" smd roundrect
			(at -0.7 0 270)
			(size 0.8 1)
			(layers "F.Cu" "F.Mask" "F.Paste")
			(roundrect_rratio 0.2)
			(net 2 "+3V3")
			(pintype "passive")
		)
		(pad "2" smd roundrect
			(at 0.7 0 270)
			(size 0.8 1)
			(layers "F.Cu" "F.Mask" "F.Paste")
			(roundrect_rratio 0.2)
			(net 351 "Net-(U13-~{FAULT})")
			(pintype "passive")
		)
	)
)
